# T6G (Grand Teton) — schematic netlist excerpt (pin names and nets, part order shuffled) for the footprints in the layout excerpt that follows; sources: Cadence DE-HDL packaged netlist, KiCad conversion of 04192023_DAF0TMB3IC0_F0TG_MB_C_brd_V02_OCP.brd

R6109  Q_RES  0 5% CHIP  pkg 0402LF  page 173 : A = JTAG_TDO ; B = JTAG_TDO_R
R6717  Q_RES  1K 1% CHIP  pkg 0201LF  page 320 : A = RT_CPU1_P0_ADDR1 ; B = GND

PL38  Q_INDUCTOR4P_14  150NH IND  pkg L_TLM117513Q-151QL_11X7-5XA  page 216
  \1\  = SW_PVDDCR_SOC_P1_SW3
  \2\  = IND_SOC_P1_CPL0
  \3\  = IND_SOC_P1_CPL3
  \4\  = PVDDCR_SOC_P1

(kicad_pcb
	(version 20260206)
	(generator "pcbnew")
	(generator_version "10.0")
	(general
		(thickness 1.6)
		(legacy_teardrops no)
	)
	(paper "A4")
	(title_block
		(title "04192023_DAF0TMB3IC0_F0TG_MB_C_brd_V02_OCP.brd")
		(comment 1 "Grand Teton / footprints 4206-4208 of 8354")
	)
	(layers
		(0 "F.Cu" signal "TOP")
		(4 "In1.Cu" signal "GND")
		(6 "In2.Cu" signal "IN1")
		(8 "In3.Cu" signal "GND1")
		(10 "In4.Cu" signal "IN2")
		(12 "In5.Cu" signal "GND2")
		(14 "In6.Cu" signal "IN3")
		(16 "In7.Cu" signal "GND3")
		(18 "In8.Cu" signal "VCC")
		(20 "In9.Cu" signal "VCC1")
		(22 "In10.Cu" signal "GND4")
		(24 "In11.Cu" signal "IN4")
		(26 "In12.Cu" signal "GND5")
		(28 "In13.Cu" signal "IN5")
		(30 "In14.Cu" signal "GND6")
		(32 "In15.Cu" signal "IN6")
		(34 "In16.Cu" signal "GND7")
		(2 "B.Cu" signal "BOTTOM")
		(9 "F.Adhes" user "F.Adhesive")
		(11 "B.Adhes" user "B.Adhesive")
		(13 "F.Paste" user "Package Geometry/Pastemask Top")
		(15 "B.Paste" user "Package Geometry/Pastemask Bottom")
		(5 "F.SilkS" user "Ref Des/Silkscreen Top")
		(7 "B.SilkS" user "Ref Des/Silkscreen Bottom")
		(1 "F.Mask" user "Board Geometry/Soldermask Top")
		(3 "B.Mask" user "Board Geometry/Soldermask Bottom")
		(17 "Dwgs.User" user "User.Drawings")
		(19 "Cmts.User" user "User.Comments")
		(21 "Eco1.User" user "User.Eco1")
		(23 "Eco2.User" user "User.Eco2")
		(25 "Edge.Cuts" user "Board Geometry/Outline")
		(27 "Margin" user)
		(31 "F.CrtYd" user "Package Geometry/Place Bound Top")
		(29 "B.CrtYd" user "Package Geometry/Place Bound Bottom")
		(35 "F.Fab" user "Ref Des/Assembly Top")
		(33 "B.Fab" user "Ref Des/Assembly Bottom")
	)
	(footprint ""
		(layer "F.Cu")
		(at 129.483104 -51.410616)
		(property "Reference" "R6109"
			(at 0 0 0)
			(layer "F.SilkS")
			(hide yes)
			(effects
				(font
					(size 1.27 1.27)
				)
			)
		)
		(property "Value" ""
			(at 0 0 0)
			(layer "F.Fab")
			(effects
				(font
					(size 1.27 1.27)
				)
			)
		)
		(duplicate_pad_numbers_are_jumpers no)
		(fp_line
			(start -0.7874 -0.4064)
			(end 0.7874 -0.4064)
			(stroke
				(width 0.1524)
				(type default)
			)
			(layer "F.SilkS")
		)
		(fp_line
			(start -0.7874 0.4064)
			(end -0.7874 -0.4064)
			(stroke
				(width 0.1524)
				(type default)
			)
			(layer "F.SilkS")
		)
		(fp_line
			(start 0.7874 -0.4064)
			(end 0.7874 0.4064)
			(stroke
				(width 0.1524)
				(type default)
			)
			(layer "F.SilkS")
		)
		(fp_line
			(start 0.7874 0.4064)
			(end -0.7874 0.4064)
			(stroke
				(width 0.1524)
				(type default)
			)
			(layer "F.SilkS")
		)
		(fp_line
			(start -0.67945 -0.305054)
			(end -0.12065 -0.305054)
			(stroke
				(width 0.1)
				(type default)
			)
			(layer "F.Fab")
		)
		(fp_line
			(start -0.67945 0.3048)
			(end -0.67945 -0.305054)
			(stroke
				(width 0.1)
				(type default)
			)
			(layer "F.Fab")
		)
		(fp_line
			(start -0.12065 -0.305054)
			(end -0.12065 -0.2794)
			(stroke
				(width 0.1)
				(type default)
			)
			(layer "F.Fab")
		)
		(fp_line
			(start -0.12065 -0.2794)
			(end 0.12065 -0.2794)
			(stroke
				(width 0.1)
				(type default)
			)
			(layer "F.Fab")
		)
		(fp_line
			(start -0.12065 0.2794)
			(end -0.12065 0.3048)
			(stroke
				(width 0.1)
				(type default)
			)
			(layer "F.Fab")
		)
		(fp_line
			(start -0.12065 0.3048)
			(end -0.67945 0.3048)
			(stroke
				(width 0.1)
				(type default)
			)
			(layer "F.Fab")
		)
		(fp_line
			(start 0.120396 0.2794)
			(end -0.12065 0.2794)
			(stroke
				(width 0.1)
				(type default)
			)
			(layer "F.Fab")
		)
		(fp_line
			(start 0.120396 0.3048)
			(end 0.120396 0.2794)
			(stroke
				(width 0.1)
				(type default)
			)
			(layer "F.Fab")
		)
		(fp_line
			(start 0.12065 -0.3048)
			(end 0.67945 -0.3048)
			(stroke
				(width 0.1)
				(type default)
			)
			(layer "F.Fab")
		)
		(fp_line
			(start 0.12065 -0.2794)
			(end 0.12065 -0.3048)
			(stroke
				(width 0.1)
				(type default)
			)
			(layer "F.Fab")
		)
		(fp_line
			(start 0.67945 -0.3048)
			(end 0.67945 0.3048)
			(stroke
				(width 0.1)
				(type default)
			)
			(layer "F.Fab")
		)
		(fp_line
			(start 0.67945 0.3048)
			(end 0.120396 0.3048)
			(stroke
				(width 0.1)
				(type default)
			)
			(layer "F.Fab")
		)
		(pad "1" smd circle
			(at -0.40005 0)
			(size 0 0)
			(layers "F.Cu" "F.Mask" "F.Paste")
			(net "JTAG_TDO")
		)
		(pad "2" smd circle
			(at 0.40005 0)
			(size 0 0)
			(layers "F.Cu" "F.Mask" "F.Paste")
			(net "JTAG_TDO_R")
		)
	)
	(footprint ""
		(layer "F.Cu")
		(at 132.603748 -165.848284 180)
		(property "Reference" "PL38"
			(at -0.737108 7.266178 0)
			(unlocked yes)
			(layer "F.SilkS")
			(effects
				(font
					(size 0.7874 0.5842)
					(thickness 0.1524)
				)
				(justify left)
			)
		)
		(property "Value" ""
			(at 0 0 180)
			(layer "F.Fab")
			(effects
				(font
					(size 1.27 1.27)
				)
			)
		)
		(duplicate_pad_numbers_are_jumpers no)
		(fp_line
			(start 3.750056 5.500116)
			(end 3.750056 -5.500116)
			(stroke
				(width 0.1524)
				(type default)
			)
			(layer "F.SilkS")
		)
		(fp_line
			(start 3.750056 -5.500116)
			(end 2.393442 -5.500116)
			(stroke
				(width 0.1524)
				(type default)
			)
			(layer "F.SilkS")
		)
		(fp_line
			(start 2.393442 5.500116)
			(end 3.750056 5.500116)
			(stroke
				(width 0.1524)
				(type default)
			)
			(layer "F.SilkS")
		)
		(fp_line
			(start -2.393442 5.500116)
			(end -3.750056 5.500116)
			(stroke
				(width 0.1524)
				(type default)
			)
			(layer "F.SilkS")
		)
		(fp_line
			(start -3.750056 5.500116)
			(end -3.750056 -5.500116)
			(stroke
				(width 0.1524)
				(type default)
			)
			(layer "F.SilkS")
		)
		(fp_line
			(start -3.750056 -5.500116)
			(end -2.393442 -5.500116)
			(stroke
				(width 0.1524)
				(type default)
			)
			(layer "F.SilkS")
		)
		(fp_poly
			(pts
				(xy -3.9116 -4.249928) (xy -4.556252 -3.927602) (xy -4.556252 -4.572254)
			)
			(stroke
				(width 0)
				(type default)
			)
			(fill yes)
			(layer "F.SilkS")
		)
		(fp_line
			(start 3.750056 5.500116)
			(end 3.750056 -5.500116)
			(stroke
				(width 0.1)
				(type default)
			)
			(layer "F.Fab")
		)
		(fp_line
			(start 3.750056 -5.500116)
			(end -3.750056 -5.500116)
			(stroke
				(width 0.1)
				(type default)
			)
			(layer "F.Fab")
		)
		(fp_line
			(start -3.750056 5.500116)
			(end 3.750056 5.500116)
			(stroke
				(width 0.1)
				(type default)
			)
			(layer "F.Fab")
		)
		(fp_line
			(start -3.750056 -5.500116)
			(end -3.750056 5.500116)
			(stroke
				(width 0.1)
				(type default)
			)
			(layer "F.Fab")
		)
		(fp_poly
			(pts
				(xy -4.9276 -4.757928) (xy -4.9276 -3.741928) (xy -3.9116 -4.249928)
			)
			(stroke
				(width 0)
				(type default)
			)
			(fill yes)
			(layer "F.Fab")
		)
		(pad "1" smd rect
			(at 0 -4.249928 90)
			(size 2.413 4.5212)
			(layers "F.Cu" "F.Mask" "F.Paste")
			(net "SW_PVDDCR_SOC_P1_SW3")
		)
		(pad "2" smd rect
			(at 0 -1.175004 90)
			(size 1.3716 4.5212)
			(layers "F.Cu" "F.Mask" "F.Paste")
			(net "IND_SOC_P1_CPL0")
		)
		(pad "3" smd rect
			(at 0 1.175004 90)
			(size 1.3716 4.5212)
			(layers "F.Cu" "F.Mask" "F.Paste")
			(net "IND_SOC_P1_CPL3")
		)
		(pad "4" smd rect
			(at 0 4.249928 90)
			(size 2.413 4.5212)
			(layers "F.Cu" "F.Mask" "F.Paste")
			(net "PVDDCR_SOC_P1")
		)
	)
	(footprint ""
		(layer "F.Cu")
		(at 72.2884 -382.27)
		(property "Reference" "R6717"
			(at 0 0 0)
			(layer "F.SilkS")
			(hide yes)
			(effects
				(font
					(size 1.27 1.27)
				)
			)
		)
		(property "Value" ""
			(at 0 0 0)
			(layer "F.Fab")
			(effects
				(font
					(size 1.27 1.27)
				)
			)
		)
		(duplicate_pad_numbers_are_jumpers no)
		(fp_line
			(start -0.32512 -0.175006)
			(end 0.32512 -0.175006)
			(stroke
				(width 0.1)
				(type default)
			)
			(layer "F.Fab")
		)
		(fp_line
			(start -0.32512 0.175006)
			(end -0.32512 -0.175006)
			(stroke
				(width 0.1)
				(type default)
			)
			(layer "F.Fab")
		)
		(fp_line
			(start 0.32512 -0.175006)
			(end 0.32512 0.175006)
			(stroke
				(width 0.1)
				(type default)
			)
			(layer "F.Fab")
		)
		(fp_line
			(start 0.32512 0.175006)
			(end -0.32512 0.175006)
			(stroke
				(width 0.1)
				(type default)
			)
			(layer "F.Fab")
		)
		(pad "1" smd rect
			(at -0.2667 0)
			(size 0.3048 0.381)
			(layers "F.Cu" "F.Mask" "F.Paste")
			(net "RT_CPU1_P0_ADDR1")
		)
		(pad "2" smd rect
			(at 0.2667 0 180)
			(size 0.3048 0.381)
			(layers "F.Cu" "F.Mask" "F.Paste")
			(net "GND")
		)
	)
)
